(kicad_pcb
	(version 20260206)
	(generator "pcbnew")
	(generator_version "10.0")
	(general
		(thickness 1.6)
		(legacy_teardrops no)
	)
	(paper "A4")
	(title_block
		(title "01162023_DA0F0TEBIF0_F0T_Expander_BD_F_brd_V02_OCP.brd")
		(comment 1 "Grand Teton / footprints 1174-1180 of 9728")
	)
	(layers
		(0 "F.Cu" signal "TOP")
		(4 "In1.Cu" signal "GND")
		(6 "In2.Cu" signal "VCC")
		(8 "In3.Cu" signal "VCC1")
		(10 "In4.Cu" signal "GND1")
		(12 "In5.Cu" signal "IN1")
		(14 "In6.Cu" signal "GND2")
		(16 "In7.Cu" signal "IN2")
		(18 "In8.Cu" signal "GND3")
		(20 "In9.Cu" signal "IN3")
		(22 "In10.Cu" signal "GND4")
		(24 "In11.Cu" signal "IN4")
		(26 "In12.Cu" signal "GND5")
		(28 "In13.Cu" signal "IN5")
		(30 "In14.Cu" signal "GND6")
		(32 "In15.Cu" signal "IN6")
		(34 "In16.Cu" signal "GND7")
		(2 "B.Cu" signal "BOTTOM")
		(9 "F.Adhes" user "F.Adhesive")
		(11 "B.Adhes" user "B.Adhesive")
		(13 "F.Paste" user "Package Geometry/Pastemask Top")
		(15 "B.Paste" user "Package Geometry/Pastemask Bottom")
		(5 "F.SilkS" user "Ref Des/Silkscreen Top")
		(7 "B.SilkS" user "Ref Des/Silkscreen Bottom")
		(1 "F.Mask" user "Board Geometry/Soldermask Top")
		(3 "B.Mask" user "Board Geometry/Soldermask Bottom")
		(17 "Dwgs.User" user "User.Drawings")
		(19 "Cmts.User" user "User.Comments")
		(21 "Eco1.User" user "User.Eco1")
		(23 "Eco2.User" user "User.Eco2")
		(25 "Edge.Cuts" user "Board Geometry/Outline")
		(27 "Margin" user)
		(31 "F.CrtYd" user "Package Geometry/Place Bound Top")
		(29 "B.CrtYd" user "Package Geometry/Place Bound Bottom")
		(35 "F.Fab" user "Ref Des/Assembly Top")
		(33 "B.Fab" user "Ref Des/Assembly Bottom")
	)
	(footprint ""
		(layer "F.Cu")
		(at 378.453396 -291.390832)
		(property "Reference" "L140"
			(at 0 0 0)
			(layer "F.SilkS")
			(hide yes)
			(effects
				(font
					(size 1.27 1.27)
				)
			)
		)
		(property "Value" ""
			(at 0 0 0)
			(layer "F.Fab")
			(effects
				(font
					(size 1.27 1.27)
				)
			)
		)
		(duplicate_pad_numbers_are_jumpers no)
		(fp_line
			(start -1.63576 -0.8128)
			(end -1.63576 0.8128)
			(stroke
				(width 0.1524)
				(type default)
			)
			(layer "F.SilkS")
		)
		(fp_line
			(start -1.63576 -0.8128)
			(end 1.63576 -0.8128)
			(stroke
				(width 0.1524)
				(type default)
			)
			(layer "F.SilkS")
		)
		(fp_line
			(start 1.63576 -0.8128)
			(end 1.63576 0.8128)
			(stroke
				(width 0.1524)
				(type default)
			)
			(layer "F.SilkS")
		)
		(fp_line
			(start 1.63576 0.8128)
			(end -1.63576 0.8128)
			(stroke
				(width 0.1524)
				(type default)
			)
			(layer "F.SilkS")
		)
		(fp_line
			(start -1.56083 -0.738632)
			(end -1.56083 0.7366)
			(stroke
				(width 0.1)
				(type default)
			)
			(layer "F.Fab")
		)
		(fp_line
			(start -1.56083 0.7366)
			(end -1.524 0.7366)
			(stroke
				(width 0.1)
				(type default)
			)
			(layer "F.Fab")
		)
		(fp_line
			(start -1.524 0.7366)
			(end 1.524 0.7366)
			(stroke
				(width 0.1)
				(type default)
			)
			(layer "F.Fab")
		)
		(fp_line
			(start 1.524 0.7366)
			(end 1.560576 0.7366)
			(stroke
				(width 0.1)
				(type default)
			)
			(layer "F.Fab")
		)
		(fp_line
			(start 1.560576 -0.738632)
			(end -1.56083 -0.738632)
			(stroke
				(width 0.1)
				(type default)
			)
			(layer "F.Fab")
		)
		(fp_line
			(start 1.560576 0.7366)
			(end 1.560576 -0.738632)
			(stroke
				(width 0.1)
				(type default)
			)
			(layer "F.Fab")
		)
		(pad "1" smd rect
			(at -0.94996 0 180)
			(size 1.1176 1.3716)
			(layers "F.Cu" "F.Mask" "F.Paste")
			(net "P1V8_PLL0_PEX3")
		)
		(pad "2" smd rect
			(at 0.94996 0 180)
			(size 1.1176 1.3716)
			(layers "F.Cu" "F.Mask" "F.Paste")
			(net "PCEPLL4_VDDA18_PEX3")
		)
	)
	(footprint ""
		(layer "F.Cu")
		(at 219.014294 -180.12918)
		(property "Reference" "R6804"
			(at 0 0 0)
			(layer "F.SilkS")
			(hide yes)
			(effects
				(font
					(size 1.27 1.27)
				)
			)
		)
		(property "Value" ""
			(at 0 0 0)
			(layer "F.Fab")
			(effects
				(font
					(size 1.27 1.27)
				)
			)
		)
		(duplicate_pad_numbers_are_jumpers no)
		(fp_line
			(start -0.7874 -0.4064)
			(end 0.7874 -0.4064)
			(stroke
				(width 0.1524)
				(type default)
			)
			(layer "F.SilkS")
		)
		(fp_line
			(start -0.7874 0.4064)
			(end -0.7874 -0.4064)
			(stroke
				(width 0.1524)
				(type default)
			)
			(layer "F.SilkS")
		)
		(fp_line
			(start 0.7874 -0.4064)
			(end 0.7874 0.4064)
			(stroke
				(width 0.1524)
				(type default)
			)
			(layer "F.SilkS")
		)
		(fp_line
			(start 0.7874 0.4064)
			(end -0.7874 0.4064)
			(stroke
				(width 0.1524)
				(type default)
			)
			(layer "F.SilkS")
		)
		(fp_line
			(start -0.67945 -0.305054)
			(end -0.12065 -0.305054)
			(stroke
				(width 0.1)
				(type default)
			)
			(layer "F.Fab")
		)
		(fp_line
			(start -0.67945 0.3048)
			(end -0.67945 -0.305054)
			(stroke
				(width 0.1)
				(type default)
			)
			(layer "F.Fab")
		)
		(fp_line
			(start -0.12065 -0.305054)
			(end -0.12065 -0.2794)
			(stroke
				(width 0.1)
				(type default)
			)
			(layer "F.Fab")
		)
		(fp_line
			(start -0.12065 -0.2794)
			(end 0.12065 -0.2794)
			(stroke
				(width 0.1)
				(type default)
			)
			(layer "F.Fab")
		)
		(fp_line
			(start -0.12065 0.2794)
			(end -0.12065 0.3048)
			(stroke
				(width 0.1)
				(type default)
			)
			(layer "F.Fab")
		)
		(fp_line
			(start -0.12065 0.3048)
			(end -0.67945 0.3048)
			(stroke
				(width 0.1)
				(type default)
			)
			(layer "F.Fab")
		)
		(fp_line
			(start 0.120396 0.2794)
			(end -0.12065 0.2794)
			(stroke
				(width 0.1)
				(type default)
			)
			(layer "F.Fab")
		)
		(fp_line
			(start 0.120396 0.3048)
			(end 0.120396 0.2794)
			(stroke
				(width 0.1)
				(type default)
			)
			(layer "F.Fab")
		)
		(fp_line
			(start 0.12065 -0.3048)
			(end 0.67945 -0.3048)
			(stroke
				(width 0.1)
				(type default)
			)
			(layer "F.Fab")
		)
		(fp_line
			(start 0.12065 -0.2794)
			(end 0.12065 -0.3048)
			(stroke
				(width 0.1)
				(type default)
			)
			(layer "F.Fab")
		)
		(fp_line
			(start 0.67945 -0.3048)
			(end 0.67945 0.3048)
			(stroke
				(width 0.1)
				(type default)
			)
			(layer "F.Fab")
		)
		(fp_line
			(start 0.67945 0.3048)
			(end 0.120396 0.3048)
			(stroke
				(width 0.1)
				(type default)
			)
			(layer "F.Fab")
		)
		(pad "1" smd circle
			(at -0.40005 0)
			(size 0 0)
			(layers "F.Cu" "F.Mask" "F.Paste")
			(net "RST_FW_BIC_PLTRST_R")
		)
		(pad "2" smd circle
			(at 0.40005 0)
			(size 0 0)
			(layers "F.Cu" "F.Mask" "F.Paste")
			(net "RST_FW_BIC_PLTRST_C")
		)
	)
	(footprint ""
		(layer "F.Cu")
		(at 408.554682 -198.603108 -90)
		(property "Reference" "R6435"
			(at 0 0 270)
			(layer "F.SilkS")
			(hide yes)
			(effects
				(font
					(size 1.27 1.27)
				)
			)
		)
		(property "Value" ""
			(at 0 0 270)
			(layer "F.Fab")
			(effects
				(font
					(size 1.27 1.27)
				)
			)
		)
		(duplicate_pad_numbers_are_jumpers no)
		(fp_line
			(start -0.7874 0.4064)
			(end -0.7874 -0.4064)
			(stroke
				(width 0.1524)
				(type default)
			)
			(layer "F.SilkS")
		)
		(fp_line
			(start 0.7874 0.4064)
			(end -0.7874 0.4064)
			(stroke
				(width 0.1524)
				(type default)
			)
			(layer "F.SilkS")
		)
		(fp_line
			(start -0.7874 -0.4064)
			(end 0.7874 -0.4064)
			(stroke
				(width 0.1524)
				(type default)
			)
			(layer "F.SilkS")
		)
		(fp_line
			(start 0.7874 -0.4064)
			(end 0.7874 0.4064)
			(stroke
				(width 0.1524)
				(type default)
			)
			(layer "F.SilkS")
		)
		(fp_line
			(start -0.67945 0.3048)
			(end -0.67945 -0.305054)
			(stroke
				(width 0.1)
				(type default)
			)
			(layer "F.Fab")
		)
		(fp_line
			(start -0.12065 0.3048)
			(end -0.67945 0.3048)
			(stroke
				(width 0.1)
				(type default)
			)
			(layer "F.Fab")
		)
		(fp_line
			(start 0.120396 0.3048)
			(end 0.120396 0.2794)
			(stroke
				(width 0.1)
				(type default)
			)
			(layer "F.Fab")
		)
		(fp_line
			(start 0.67945 0.3048)
			(end 0.120396 0.3048)
			(stroke
				(width 0.1)
				(type default)
			)
			(layer "F.Fab")
		)
		(fp_line
			(start -0.12065 0.2794)
			(end -0.12065 0.3048)
			(stroke
				(width 0.1)
				(type default)
			)
			(layer "F.Fab")
		)
		(fp_line
			(start 0.120396 0.2794)
			(end -0.12065 0.2794)
			(stroke
				(width 0.1)
				(type default)
			)
			(layer "F.Fab")
		)
		(fp_line
			(start -0.12065 -0.2794)
			(end 0.12065 -0.2794)
			(stroke
				(width 0.1)
				(type default)
			)
			(layer "F.Fab")
		)
		(fp_line
			(start 0.12065 -0.2794)
			(end 0.12065 -0.3048)
			(stroke
				(width 0.1)
				(type default)
			)
			(layer "F.Fab")
		)
		(fp_line
			(start 0.12065 -0.3048)
			(end 0.67945 -0.3048)
			(stroke
				(width 0.1)
				(type default)
			)
			(layer "F.Fab")
		)
		(fp_line
			(start 0.67945 -0.3048)
			(end 0.67945 0.3048)
			(stroke
				(width 0.1)
				(type default)
			)
			(layer "F.Fab")
		)
		(fp_line
			(start -0.67945 -0.305054)
			(end -0.12065 -0.305054)
			(stroke
				(width 0.1)
				(type default)
			)
			(layer "F.Fab")
		)
		(fp_line
			(start -0.12065 -0.305054)
			(end -0.12065 -0.2794)
			(stroke
				(width 0.1)
				(type default)
			)
			(layer "F.Fab")
		)
		(pad "1" smd circle
			(at -0.40005 0 270)
			(size 0 0)
			(layers "F.Cu" "F.Mask" "F.Paste")
			(net "FPGA_PEX1_MODE_SEL2_ISO")
		)
		(pad "2" smd circle
			(at 0.40005 0 270)
			(size 0 0)
			(layers "F.Cu" "F.Mask" "F.Paste")
			(net "PEX1_MODE_SEL2")
		)
	)
	(footprint ""
		(layer "F.Cu")
		(at 365.506 -210.947 180)
		(property "Reference" "R4624"
			(at 0 0 180)
			(layer "F.SilkS")
			(hide yes)
			(effects
				(font
					(size 1.27 1.27)
				)
			)
		)
		(property "Value" ""
			(at 0 0 180)
			(layer "F.Fab")
			(effects
				(font
					(size 1.27 1.27)
				)
			)
		)
		(duplicate_pad_numbers_are_jumpers no)
		(fp_line
			(start 0.7874 0.4064)
			(end -0.7874 0.4064)
			(stroke
				(width 0.1524)
				(type default)
			)
			(layer "F.SilkS")
		)
		(fp_line
			(start 0.7874 -0.4064)
			(end 0.7874 0.4064)
			(stroke
				(width 0.1524)
				(type default)
			)
			(layer "F.SilkS")
		)
		(fp_line
			(start -0.7874 0.4064)
			(end -0.7874 -0.4064)
			(stroke
				(width 0.1524)
				(type default)
			)
			(layer "F.SilkS")
		)
		(fp_line
			(start -0.7874 -0.4064)
			(end 0.7874 -0.4064)
			(stroke
				(width 0.1524)
				(type default)
			)
			(layer "F.SilkS")
		)
		(fp_line
			(start 0.67945 0.3048)
			(end 0.120396 0.3048)
			(stroke
				(width 0.1)
				(type default)
			)
			(layer "F.Fab")
		)
		(fp_line
			(start 0.67945 -0.3048)
			(end 0.67945 0.3048)
			(stroke
				(width 0.1)
				(type default)
			)
			(layer "F.Fab")
		)
		(fp_line
			(start 0.12065 -0.2794)
			(end 0.12065 -0.3048)
			(stroke
				(width 0.1)
				(type default)
			)
			(layer "F.Fab")
		)
		(fp_line
			(start 0.12065 -0.3048)
			(end 0.67945 -0.3048)
			(stroke
				(width 0.1)
				(type default)
			)
			(layer "F.Fab")
		)
		(fp_line
			(start 0.120396 0.3048)
			(end 0.120396 0.2794)
			(stroke
				(width 0.1)
				(type default)
			)
			(layer "F.Fab")
		)
		(fp_line
			(start 0.120396 0.2794)
			(end -0.12065 0.2794)
			(stroke
				(width 0.1)
				(type default)
			)
			(layer "F.Fab")
		)
		(fp_line
			(start -0.12065 0.3048)
			(end -0.67945 0.3048)
			(stroke
				(width 0.1)
				(type default)
			)
			(layer "F.Fab")
		)
		(fp_line
			(start -0.12065 0.2794)
			(end -0.12065 0.3048)
			(stroke
				(width 0.1)
				(type default)
			)
			(layer "F.Fab")
		)
		(fp_line
			(start -0.12065 -0.2794)
			(end 0.12065 -0.2794)
			(stroke
				(width 0.1)
				(type default)
			)
			(layer "F.Fab")
		)
		(fp_line
			(start -0.12065 -0.305054)
			(end -0.12065 -0.2794)
			(stroke
				(width 0.1)
				(type default)
			)
			(layer "F.Fab")
		)
		(fp_line
			(start -0.67945 0.3048)
			(end -0.67945 -0.305054)
			(stroke
				(width 0.1)
				(type default)
			)
			(layer "F.Fab")
		)
		(fp_line
			(start -0.67945 -0.305054)
			(end -0.12065 -0.305054)
			(stroke
				(width 0.1)
				(type default)
			)
			(layer "F.Fab")
		)
		(pad "1" smd circle
			(at -0.40005 0 180)
			(size 0 0)
			(layers "F.Cu" "F.Mask" "F.Paste")
			(net "SSD0_PEX_PWR_EN")
		)
		(pad "2" smd circle
			(at 0.40005 0 180)
			(size 0 0)
			(layers "F.Cu" "F.Mask" "F.Paste")
			(net "SSD0_PEX_PWR_EN_R")
		)
	)
	(footprint ""
		(layer "F.Cu")
		(at 67.142614 -70.844918 -90)
		(property "Reference" "PD90"
			(at 4.042918 2.117344 90)
			(unlocked yes)
			(layer "F.SilkS")
			(effects
				(font
					(size 0.7874 0.5842)
					(thickness 0.1524)
				)
				(justify left)
			)
		)
		(property "Value" ""
			(at 0 0 270)
			(layer "F.Fab")
			(effects
				(font
					(size 1.27 1.27)
				)
			)
		)
		(duplicate_pad_numbers_are_jumpers no)
		(fp_line
			(start -3.400044 1.459992)
			(end -3.400044 -1.459992)
			(stroke
				(width 0.1524)
				(type default)
			)
			(layer "F.SilkS")
		)
		(fp_line
			(start 4.107942 1.459992)
			(end -3.400044 1.459992)
			(stroke
				(width 0.1524)
				(type default)
			)
			(layer "F.SilkS")
		)
		(fp_line
			(start -3.400044 -1.459992)
			(end 4.107942 -1.459992)
			(stroke
				(width 0.1524)
				(type default)
			)
			(layer "F.SilkS")
		)
		(fp_line
			(start 4.107942 -1.459992)
			(end 4.107942 1.459992)
			(stroke
				(width 0.1524)
				(type default)
			)
			(layer "F.SilkS")
		)
		(fp_poly
			(pts
				(xy 4.107942 -1.459992) (xy 4.107942 1.459992) (xy 3.308096 1.459992) (xy 3.308096 -1.459992)
			)
			(stroke
				(width 0)
				(type default)
			)
			(fill yes)
			(layer "F.SilkS")
		)
		(fp_line
			(start -2.29997 1.459992)
			(end -2.29997 -1.459992)
			(stroke
				(width 0.1)
				(type default)
			)
			(layer "F.Fab")
		)
		(fp_line
			(start 2.29997 1.459992)
			(end -2.29997 1.459992)
			(stroke
				(width 0.1)
				(type default)
			)
			(layer "F.Fab")
		)
		(fp_line
			(start -2.29997 -1.459992)
			(end 2.29997 -1.459992)
			(stroke
				(width 0.1)
				(type default)
			)
			(layer "F.Fab")
		)
		(fp_line
			(start 2.29997 -1.459992)
			(end 2.29997 1.459992)
			(stroke
				(width 0.1)
				(type default)
			)
			(layer "F.Fab")
		)
		(fp_text user "-"
			(at 5.4102 0.29845 90)
			(unlocked yes)
			(layer "F.SilkS")
			(effects
				(font
					(size 1.905 1.4224)
					(thickness 0.1524)
				)
				(justify left)
			)
		)
		(fp_text user "+"
			(at -5.250688 0.221488 270)
			(unlocked yes)
			(layer "F.SilkS")
			(effects
				(font
					(size 1.905 1.4224)
					(thickness 0.1524)
				)
				(justify left)
			)
		)
		(fp_text user "-"
			(at 5.4102 0.29845 90)
			(unlocked yes)
			(layer "F.Fab")
			(effects
				(font
					(size 1.905 1.4224)
					(thickness 0.1524)
				)
				(justify left)
			)
		)
		(fp_text user "+"
			(at -4.7752 -0.12065 270)
			(unlocked yes)
			(layer "F.Fab")
			(effects
				(font
					(size 1.905 1.4224)
					(thickness 0.1524)
				)
				(justify left)
			)
		)
		(pad "A" smd rect
			(at -1.999996 0)
			(size 1.7018 2.5146)
			(layers "F.Cu" "F.Mask" "F.Paste")
			(net "GND")
		)
		(pad "C" smd rect
			(at 1.999996 0)
			(size 1.7018 2.5146)
			(layers "F.Cu" "F.Mask" "F.Paste")
			(net "P12V_SSD2_R")
		)
	)
	(footprint ""
		(layer "F.Cu")
		(at 257.179318 -262.645652 90)
		(property "Reference" "C3419"
			(at 0 0 90)
			(layer "F.SilkS")
			(hide yes)
			(effects
				(font
					(size 1.27 1.27)
				)
			)
		)
		(property "Value" ""
			(at 0 0 90)
			(layer "F.Fab")
			(effects
				(font
					(size 1.27 1.27)
				)
			)
		)
		(duplicate_pad_numbers_are_jumpers no)
		(fp_line
			(start 0.299974 -0.150114)
			(end 0.299974 0.150114)
			(stroke
				(width 0.1)
				(type default)
			)
			(layer "F.Fab")
		)
		(fp_line
			(start -0.299974 -0.150114)
			(end 0.299974 -0.150114)
			(stroke
				(width 0.1)
				(type default)
			)
			(layer "F.Fab")
		)
		(fp_line
			(start 0.299974 0.150114)
			(end -0.299974 0.150114)
			(stroke
				(width 0.1)
				(type default)
			)
			(layer "F.Fab")
		)
		(fp_line
			(start -0.299974 0.150114)
			(end -0.299974 -0.150114)
			(stroke
				(width 0.1)
				(type default)
			)
			(layer "F.Fab")
		)
		(pad "1" smd rect
			(at -0.2667 0 90)
			(size 0.3048 0.381)
			(layers "F.Cu" "F.Mask" "F.Paste")
			(net "P1V8_VDDA_PEX2")
		)
		(pad "2" smd rect
			(at 0.2667 0 90)
			(size 0.3048 0.381)
			(layers "F.Cu" "F.Mask" "F.Paste")
			(net "GND")
		)
	)
	(footprint ""
		(layer "F.Cu")
		(at 121.930668 -280.44902 -90)
		(property "Reference" "PR108"
			(at 0 0 270)
			(layer "F.SilkS")
			(hide yes)
			(effects
				(font
					(size 1.27 1.27)
				)
			)
		)
		(property "Value" ""
			(at 0 0 270)
			(layer "F.Fab")
			(effects
				(font
					(size 1.27 1.27)
				)
			)
		)
		(duplicate_pad_numbers_are_jumpers no)
		(fp_line
			(start -0.7874 0.4064)
			(end -0.7874 -0.4064)
			(stroke
				(width 0.1524)
				(type default)
			)
			(layer "F.SilkS")
		)
		(fp_line
			(start 0.7874 0.4064)
			(end -0.7874 0.4064)
			(stroke
				(width 0.1524)
				(type default)
			)
			(layer "F.SilkS")
		)
		(fp_line
			(start -0.7874 -0.4064)
			(end 0.7874 -0.4064)
			(stroke
				(width 0.1524)
				(type default)
			)
			(layer "F.SilkS")
		)
		(fp_line
			(start 0.7874 -0.4064)
			(end 0.7874 0.4064)
			(stroke
				(width 0.1524)
				(type default)
			)
			(layer "F.SilkS")
		)
		(fp_line
			(start -0.67945 0.3048)
			(end -0.67945 -0.305054)
			(stroke
				(width 0.1)
				(type default)
			)
			(layer "F.Fab")
		)
		(fp_line
			(start -0.12065 0.3048)
			(end -0.67945 0.3048)
			(stroke
				(width 0.1)
				(type default)
			)
			(layer "F.Fab")
		)
		(fp_line
			(start 0.120396 0.3048)
			(end 0.120396 0.2794)
			(stroke
				(width 0.1)
				(type default)
			)
			(layer "F.Fab")
		)
		(fp_line
			(start 0.67945 0.3048)
			(end 0.120396 0.3048)
			(stroke
				(width 0.1)
				(type default)
			)
			(layer "F.Fab")
		)
		(fp_line
			(start -0.12065 0.2794)
			(end -0.12065 0.3048)
			(stroke
				(width 0.1)
				(type default)
			)
			(layer "F.Fab")
		)
		(fp_line
			(start 0.120396 0.2794)
			(end -0.12065 0.2794)
			(stroke
				(width 0.1)
				(type default)
			)
			(layer "F.Fab")
		)
		(fp_line
			(start -0.12065 -0.2794)
			(end 0.12065 -0.2794)
			(stroke
				(width 0.1)
				(type default)
			)
			(layer "F.Fab")
		)
		(fp_line
			(start 0.12065 -0.2794)
			(end 0.12065 -0.3048)
			(stroke
				(width 0.1)
				(type default)
			)
			(layer "F.Fab")
		)
		(fp_line
			(start 0.12065 -0.3048)
			(end 0.67945 -0.3048)
			(stroke
				(width 0.1)
				(type default)
			)
			(layer "F.Fab")
		)
		(fp_line
			(start 0.67945 -0.3048)
			(end 0.67945 0.3048)
			(stroke
				(width 0.1)
				(type default)
			)
			(layer "F.Fab")
		)
		(fp_line
			(start -0.67945 -0.305054)
			(end -0.12065 -0.305054)
			(stroke
				(width 0.1)
				(type default)
			)
			(layer "F.Fab")
		)
		(fp_line
			(start -0.12065 -0.305054)
			(end -0.12065 -0.2794)
			(stroke
				(width 0.1)
				(type default)
			)
			(layer "F.Fab")
		)
		(pad "1" smd circle
			(at -0.40005 0 270)
			(size 0 0)
			(layers "F.Cu" "F.Mask" "F.Paste")
			(net "SW_P0V8_PEX1_BOOT1")
		)
		(pad "2" smd circle
			(at 0.40005 0 270)
			(size 0 0)
			(layers "F.Cu" "F.Mask" "F.Paste")
			(net "SW_P0V8_PEX1_BOOT1_R")
		)
	)
)
